(kicad_pcb
	(version 20260206)
	(generator "pcbnew")
	(generator_version "10.0")
	(general
		(thickness 1.6)
		(legacy_teardrops no)
	)
	(paper "A4")
	(title_block
		(title "baseboard — 13948-1b.1110WZS1818.brd")
		(comment 1 "Honey Badger (Wiwynn) / footprints 804-808 of 2523")
	)
	(layers
		(0 "F.Cu" signal "TOP")
		(4 "In1.Cu" signal "L2GND")
		(6 "In2.Cu" signal "L3")
		(8 "In3.Cu" signal "L4VCC")
		(10 "In4.Cu" signal "L5VCC")
		(12 "In5.Cu" signal "L6")
		(14 "In6.Cu" signal "L7GND")
		(2 "B.Cu" signal "BOTTOM")
		(9 "F.Adhes" user "F.Adhesive")
		(11 "B.Adhes" user "B.Adhesive")
		(13 "F.Paste" user "Package Geometry/Pastemask Top")
		(15 "B.Paste" user "Package Geometry/Pastemask Bottom")
		(5 "F.SilkS" user "Ref Des/Silkscreen Top")
		(7 "B.SilkS" user "Ref Des/Silkscreen Bottom")
		(1 "F.Mask" user "Board Geometry/Soldermask Top")
		(3 "B.Mask" user "Board Geometry/Soldermask Bottom")
		(17 "Dwgs.User" user "User.Drawings")
		(19 "Cmts.User" user "User.Comments")
		(21 "Eco1.User" user "User.Eco1")
		(23 "Eco2.User" user "User.Eco2")
		(25 "Edge.Cuts" user "Board Geometry/Outline")
		(27 "Margin" user)
		(31 "F.CrtYd" user "Package Geometry/Place Bound Top")
		(29 "B.CrtYd" user "Package Geometry/Place Bound Bottom")
		(35 "F.Fab" user "Ref Des/Assembly Top")
		(33 "B.Fab" user "Ref Des/Assembly Bottom")
	)
	(footprint ""
		(layer "F.Cu")
		(at 262.944864 -224.654872 -90)
		(property "Reference" "PU6"
			(at 0 0 270)
			(layer "F.SilkS")
			(hide yes)
			(effects
				(font
					(size 1.27 1.27)
				)
			)
		)
		(property "Value" "TPS74801RGW-GP"
			(at -4.7244 -6.223 270)
			(unlocked yes)
			(layer "F.Fab")
			(hide yes)
			(effects
				(font
					(size 1.016 1.016)
					(thickness 0.1524)
				)
			)
		)
		(property "Device Type" "QFN20-1G3D15H40"
			(at -4.7244 -7.747 270)
			(unlocked yes)
			(layer "F.Fab")
			(hide yes)
			(effects
				(font
					(size 1.016 1.016)
					(thickness 0.1524)
				)
			)
		)
		(duplicate_pad_numbers_are_jumpers no)
		(fp_line
			(start -3.5179 3.5179)
			(end -2.2479 3.5179)
			(stroke
				(width 0.1524)
				(type default)
			)
			(layer "F.SilkS")
		)
		(fp_line
			(start 2.2479 3.5179)
			(end 3.5179 3.5179)
			(stroke
				(width 0.1524)
				(type default)
			)
			(layer "F.SilkS")
		)
		(fp_line
			(start 3.5179 3.5179)
			(end 3.5179 2.2479)
			(stroke
				(width 0.1524)
				(type default)
			)
			(layer "F.SilkS")
		)
		(fp_line
			(start 1.299972 3.160522)
			(end 1.299972 3.668522)
			(stroke
				(width 0.1524)
				(type default)
			)
			(layer "F.SilkS")
		)
		(fp_line
			(start -3.5179 2.2479)
			(end -3.5179 3.5179)
			(stroke
				(width 0.1524)
				(type default)
			)
			(layer "F.SilkS")
		)
		(fp_line
			(start -3.160522 1.299972)
			(end -3.922522 1.299972)
			(stroke
				(width 0.1524)
				(type default)
			)
			(layer "F.SilkS")
		)
		(fp_line
			(start 3.160522 -1.299972)
			(end 3.922522 -1.299972)
			(stroke
				(width 0.1524)
				(type default)
			)
			(layer "F.SilkS")
		)
		(fp_line
			(start -1.299972 -3.160522)
			(end -1.299972 -3.668522)
			(stroke
				(width 0.1524)
				(type default)
			)
			(layer "F.SilkS")
		)
		(fp_line
			(start -3.5179 -3.5179)
			(end -3.5179 -2.2479)
			(stroke
				(width 0.1524)
				(type default)
			)
			(layer "F.SilkS")
		)
		(fp_line
			(start -2.2479 -3.5179)
			(end -3.5179 -3.5179)
			(stroke
				(width 0.1524)
				(type default)
			)
			(layer "F.SilkS")
		)
		(fp_poly
			(pts
				(xy 3.5179 -3.5179) (xy 2.2479 -3.5179) (xy 3.5179 -2.2479)
			)
			(stroke
				(width 0)
				(type default)
			)
			(fill yes)
			(layer "F.SilkS")
		)
		(fp_rect
			(start -2.5019 2.5019)
			(end 2.5019 -2.5019)
			(stroke
				(width 0)
				(type default)
			)
			(fill no)
			(layer "F.CrtYd")
		)
		(fp_poly
			(pts
				(xy -3.5179 3.5179) (xy -3.5179 -3.5179) (xy 3.5179 -3.5179) (xy 3.5179 -2.5019) (xy -2.5019 -2.5019)
				(xy -2.5019 2.5019) (xy 2.5019 2.5019) (xy 2.5019 -2.49682) (xy 3.5179 -2.49682) (xy 3.5179 3.5179)
			)
			(stroke
				(width 0)
				(type default)
			)
			(fill no)
			(layer "F.CrtYd")
		)
		(fp_rect
			(start -3.5179 3.5179)
			(end 3.5179 -3.5179)
			(stroke
				(width 0)
				(type default)
			)
			(fill no)
			(layer "F.Fab")
		)
		(pad "1" smd rect
			(at 1.299972 -2.474722 270)
			(size 0.3556 1.0668)
			(layers "F.Cu" "F.Mask" "F.Paste")
			(net "TPS74801_1V26_STBY_OUT")
		)
		(pad "2" smd rect
			(at 0.649986 -2.474722 270)
			(size 0.3556 1.0668)
			(layers "F.Cu" "F.Mask" "F.Paste")
			(net "GND")
		)
		(pad "3" smd rect
			(at 0 -2.474722 270)
			(size 0.3556 1.0668)
			(layers "F.Cu" "F.Mask" "F.Paste")
			(net "GND")
		)
		(pad "4" smd rect
			(at -0.649986 -2.474722 270)
			(size 0.3556 1.0668)
			(layers "F.Cu" "F.Mask" "F.Paste")
			(net "GND")
		)
		(pad "5" smd rect
			(at -1.299972 -2.474722 270)
			(size 0.3556 1.0668)
			(layers "F.Cu" "F.Mask" "F.Paste")
			(net "TPS74801_P1V26_STBY_IN")
		)
		(pad "6" smd rect
			(at -2.474722 -1.299972 270)
			(size 1.0668 0.3556)
			(layers "F.Cu" "F.Mask" "F.Paste")
			(net "TPS74801_P1V26_STBY_IN")
		)
		(pad "7" smd rect
			(at -2.474722 -0.649986 270)
			(size 1.0668 0.3556)
			(layers "F.Cu" "F.Mask" "F.Paste")
			(net "TPS74801_P1V26_STBY_IN")
		)
		(pad "8" smd rect
			(at -2.474722 0 270)
			(size 1.0668 0.3556)
			(layers "F.Cu" "F.Mask" "F.Paste")
			(net "TPS74801_P1V26_STBY_IN")
		)
		(pad "9" smd rect
			(at -2.474722 0.649986 270)
			(size 1.0668 0.3556)
			(layers "F.Cu" "F.Mask" "F.Paste")
			(net "P1V26_STBY_PG")
		)
		(pad "10" smd rect
			(at -2.474722 1.299972 270)
			(size 1.0668 0.3556)
			(layers "F.Cu" "F.Mask" "F.Paste")
			(net "TPS74801_1V26_STBY_BIAS")
		)
		(pad "11" smd rect
			(at -1.299972 2.474722 270)
			(size 0.3556 1.0668)
			(layers "F.Cu" "F.Mask" "F.Paste")
			(net "TPS74801_1V26_STBY_EN")
		)
		(pad "12" smd rect
			(at -0.649986 2.474722 270)
			(size 0.3556 1.0668)
			(layers "F.Cu" "F.Mask" "F.Paste")
			(net "GND")
		)
		(pad "13" smd rect
			(at 0 2.474722 270)
			(size 0.3556 1.0668)
			(layers "F.Cu" "F.Mask" "F.Paste")
			(net "GND")
		)
		(pad "14" smd rect
			(at 0.649986 2.474722 270)
			(size 0.3556 1.0668)
			(layers "F.Cu" "F.Mask" "F.Paste")
			(net "GND")
		)
		(pad "15" smd rect
			(at 1.299972 2.474722 270)
			(size 0.3556 1.0668)
			(layers "F.Cu" "F.Mask" "F.Paste")
			(net "TPS74801_1V26_STBY_SS")
		)
		(pad "16" smd rect
			(at 2.474722 1.299972 270)
			(size 1.0668 0.3556)
			(layers "F.Cu" "F.Mask" "F.Paste")
			(net "TPS74801_1V26_STBY_FB")
		)
		(pad "17" smd rect
			(at 2.474722 0.649986 270)
			(size 1.0668 0.3556)
			(layers "F.Cu" "F.Mask" "F.Paste")
			(net "GND")
		)
		(pad "18" smd rect
			(at 2.474722 0 270)
			(size 1.0668 0.3556)
			(layers "F.Cu" "F.Mask" "F.Paste")
			(net "TPS74801_1V26_STBY_OUT")
		)
		(pad "19" smd rect
			(at 2.474722 -0.649986 270)
			(size 1.0668 0.3556)
			(layers "F.Cu" "F.Mask" "F.Paste")
			(net "TPS74801_1V26_STBY_OUT")
		)
		(pad "20" smd rect
			(at 2.474722 -1.299972 270)
			(size 1.0668 0.3556)
			(layers "F.Cu" "F.Mask" "F.Paste")
			(net "TPS74801_1V26_STBY_OUT")
		)
		(pad "21" smd rect
			(at 0 0 270)
			(size 3.2512 3.2512)
			(layers "F.Cu" "F.Mask" "F.Paste")
			(net "GND")
		)
	)
	(footprint ""
		(layer "F.Cu")
		(at 220.976698 -21.876004 180)
		(property "Reference" "Q6"
			(at 0 0 180)
			(layer "F.SilkS")
			(hide yes)
			(effects
				(font
					(size 1.27 1.27)
				)
			)
		)
		(property "Value" "2N7002A-7-GP"
			(at 0.127 -8.9662 180)
			(unlocked yes)
			(layer "F.Fab")
			(hide yes)
			(effects
				(font
					(size 1.016 1.016)
					(thickness 0.1524)
				)
			)
		)
		(property "Device Type" "SOT23DGS2D4H48"
			(at 0.127 -10.4902 180)
			(unlocked yes)
			(layer "F.Fab")
			(hide yes)
			(effects
				(font
					(size 1.016 1.016)
					(thickness 0.1524)
				)
			)
		)
		(duplicate_pad_numbers_are_jumpers no)
		(fp_line
			(start 1.651 1.778)
			(end 1.651 -1.778)
			(stroke
				(width 0.1524)
				(type default)
			)
			(layer "F.SilkS")
		)
		(fp_line
			(start 1.651 -1.778)
			(end -1.651 -1.778)
			(stroke
				(width 0.1524)
				(type default)
			)
			(layer "F.SilkS")
		)
		(fp_line
			(start -1.651 1.778)
			(end 1.651 1.778)
			(stroke
				(width 0.1524)
				(type default)
			)
			(layer "F.SilkS")
		)
		(fp_line
			(start -1.651 -1.778)
			(end -1.651 1.778)
			(stroke
				(width 0.1524)
				(type default)
			)
			(layer "F.SilkS")
		)
		(fp_poly
			(pts
				(xy -1.778 1.8796) (xy -1.778 -1.8796) (xy 1.778 -1.8796) (xy 1.778 1.8796)
			)
			(stroke
				(width 0)
				(type default)
			)
			(fill no)
			(layer "F.CrtYd")
		)
		(fp_poly
			(pts
				(xy -1.778 1.8796) (xy -1.778 -1.8796) (xy 1.778 -1.8796) (xy 1.778 1.8796)
			)
			(stroke
				(width 0)
				(type default)
			)
			(fill no)
			(layer "F.Fab")
		)
		(pad "D" smd custom
			(at 0 -0.9525 180)
			(size 0.1905 0.1905)
			(layers "F.Cu" "F.Mask" "F.Paste")
			(net "LED_PWR_N_ON")
			(options
				(clearance outline)
				(anchor circle)
			)
			(primitives
				(gr_poly
					(pts
						(arc
							(start -0.1778 0.5715)
							(mid -0.321484 0.511984)
							(end -0.381 0.3683)
						)
						(arc
							(start -0.381 -0.3683)
							(mid -0.321484 -0.511984)
							(end -0.1778 -0.5715)
						)
						(arc
							(start 0.1778 -0.5715)
							(mid 0.321484 -0.511984)
							(end 0.381 -0.3683)
						)
						(arc
							(start 0.381 0.3683)
							(mid 0.321484 0.511984)
							(end 0.1778 0.5715)
						)
					)
					(width 0)
					(fill yes)
				)
			)
		)
		(pad "G" smd custom
			(at -0.98425 0.9525 180)
			(size 0.1905 0.1905)
			(layers "F.Cu" "F.Mask" "F.Paste")
			(net "BMC_ID_LED_R")
			(options
				(clearance outline)
				(anchor circle)
			)
			(primitives
				(gr_poly
					(pts
						(arc
							(start -0.1778 0.5715)
							(mid -0.321484 0.511984)
							(end -0.381 0.3683)
						)
						(arc
							(start -0.381 -0.3683)
							(mid -0.321484 -0.511984)
							(end -0.1778 -0.5715)
						)
						(arc
							(start 0.1778 -0.5715)
							(mid 0.321484 -0.511984)
							(end 0.381 -0.3683)
						)
						(arc
							(start 0.381 0.3683)
							(mid 0.321484 0.511984)
							(end 0.1778 0.5715)
						)
					)
					(width 0)
					(fill yes)
				)
			)
		)
		(pad "S" smd custom
			(at 0.98425 0.9525 180)
			(size 0.1905 0.1905)
			(layers "F.Cu" "F.Mask" "F.Paste")
			(net "GND")
			(options
				(clearance outline)
				(anchor circle)
			)
			(primitives
				(gr_poly
					(pts
						(arc
							(start -0.1778 0.5715)
							(mid -0.321484 0.511984)
							(end -0.381 0.3683)
						)
						(arc
							(start -0.381 -0.3683)
							(mid -0.321484 -0.511984)
							(end -0.1778 -0.5715)
						)
						(arc
							(start 0.1778 -0.5715)
							(mid 0.321484 -0.511984)
							(end 0.381 -0.3683)
						)
						(arc
							(start 0.381 0.3683)
							(mid 0.321484 0.511984)
							(end 0.1778 0.5715)
						)
					)
					(width 0)
					(fill yes)
				)
			)
		)
	)
	(footprint ""
		(layer "F.Cu")
		(at 183.134 -49.149 90)
		(property "Reference" "R490"
			(at 0 0 90)
			(layer "F.SilkS")
			(hide yes)
			(effects
				(font
					(size 1.27 1.27)
				)
			)
		)
		(property "Value" "4K7R2F-GP"
			(at 0.064008 -3.993896 90)
			(unlocked yes)
			(layer "F.Fab")
			(hide yes)
			(effects
				(font
					(size 1.016 1.016)
					(thickness 0.1524)
				)
			)
		)
		(property "Device Type" "R402H16"
			(at 0.064008 -5.517896 90)
			(unlocked yes)
			(layer "F.Fab")
			(hide yes)
			(effects
				(font
					(size 1.016 1.016)
					(thickness 0.1524)
				)
			)
		)
		(duplicate_pad_numbers_are_jumpers no)
		(fp_line
			(start 0.508 -0.9398)
			(end -0.508 -0.9398)
			(stroke
				(width 0.1524)
				(type default)
			)
			(layer "F.SilkS")
		)
		(fp_line
			(start -0.508 -0.9398)
			(end -0.508 0.9398)
			(stroke
				(width 0.1524)
				(type default)
			)
			(layer "F.SilkS")
		)
		(fp_rect
			(start -0.508 0.9398)
			(end 0.508 -0.9398)
			(stroke
				(width 0)
				(type default)
			)
			(fill no)
			(layer "F.CrtYd")
		)
		(fp_rect
			(start -0.508 0.9398)
			(end 0.508 -0.9398)
			(stroke
				(width 0)
				(type default)
			)
			(fill no)
			(layer "F.Fab")
		)
		(pad "1" smd custom
			(at 0 -0.4445 90)
			(size 0.1397 0.1397)
			(layers "F.Cu" "F.Mask" "F.Paste")
			(net "P3V3_STBY")
			(options
				(clearance outline)
				(anchor circle)
			)
			(primitives
				(gr_poly
					(pts
						(arc
							(start -0.1778 -0.2794)
							(mid -0.249642 -0.249642)
							(end -0.2794 -0.1778)
						)
						(arc
							(start -0.2794 0.1778)
							(mid -0.249642 0.249642)
							(end -0.1778 0.2794)
						)
						(arc
							(start 0.1778 0.2794)
							(mid 0.249642 0.249642)
							(end 0.2794 0.1778)
						)
						(arc
							(start 0.2794 -0.1778)
							(mid 0.249642 -0.249642)
							(end 0.1778 -0.2794)
						)
					)
					(width 0)
					(fill yes)
				)
			)
		)
		(pad "2" smd custom
			(at 0 0.4445 90)
			(size 0.1397 0.1397)
			(layers "F.Cu" "F.Mask" "F.Paste")
			(net "PRSNT_AND_2")
			(options
				(clearance outline)
				(anchor circle)
			)
			(primitives
				(gr_poly
					(pts
						(arc
							(start -0.1778 -0.2794)
							(mid -0.249642 -0.249642)
							(end -0.2794 -0.1778)
						)
						(arc
							(start -0.2794 0.1778)
							(mid -0.249642 0.249642)
							(end -0.1778 0.2794)
						)
						(arc
							(start 0.1778 0.2794)
							(mid 0.249642 0.249642)
							(end 0.2794 0.1778)
						)
						(arc
							(start 0.2794 -0.1778)
							(mid 0.249642 -0.249642)
							(end 0.1778 -0.2794)
						)
					)
					(width 0)
					(fill yes)
				)
			)
		)
	)
	(footprint ""
		(layer "F.Cu")
		(at 292.481 -159.639)
		(property "Reference" "R617"
			(at 0 0 0)
			(layer "F.SilkS")
			(hide yes)
			(effects
				(font
					(size 1.27 1.27)
				)
			)
		)
		(property "Value" "0R2J-2-GP"
			(at 0.064008 -3.993896 0)
			(unlocked yes)
			(layer "F.Fab")
			(hide yes)
			(effects
				(font
					(size 1.016 1.016)
					(thickness 0.1524)
				)
			)
		)
		(property "Device Type" "R402H16"
			(at 0.064008 -5.517896 0)
			(unlocked yes)
			(layer "F.Fab")
			(hide yes)
			(effects
				(font
					(size 1.016 1.016)
					(thickness 0.1524)
				)
			)
		)
		(duplicate_pad_numbers_are_jumpers no)
		(fp_line
			(start -0.508 -0.9398)
			(end -0.508 0.9398)
			(stroke
				(width 0.1524)
				(type default)
			)
			(layer "F.SilkS")
		)
		(fp_line
			(start 0.508 -0.9398)
			(end -0.508 -0.9398)
			(stroke
				(width 0.1524)
				(type default)
			)
			(layer "F.SilkS")
		)
		(fp_rect
			(start -0.508 0.9398)
			(end 0.508 -0.9398)
			(stroke
				(width 0)
				(type default)
			)
			(fill no)
			(layer "F.CrtYd")
		)
		(fp_rect
			(start -0.508 0.9398)
			(end 0.508 -0.9398)
			(stroke
				(width 0)
				(type default)
			)
			(fill no)
			(layer "F.Fab")
		)
		(pad "1" smd custom
			(at 0 -0.4445)
			(size 0.1397 0.1397)
			(layers "F.Cu" "F.Mask" "F.Paste")
			(net "BMC_HDD_PRE_INT_N")
			(options
				(clearance outline)
				(anchor circle)
			)
			(primitives
				(gr_poly
					(pts
						(arc
							(start -0.1778 -0.2794)
							(mid -0.249642 -0.249642)
							(end -0.2794 -0.1778)
						)
						(arc
							(start -0.2794 0.1778)
							(mid -0.249642 0.249642)
							(end -0.1778 0.2794)
						)
						(arc
							(start 0.1778 0.2794)
							(mid 0.249642 0.249642)
							(end 0.2794 0.1778)
						)
						(arc
							(start 0.2794 -0.1778)
							(mid 0.249642 -0.249642)
							(end 0.1778 -0.2794)
						)
					)
					(width 0)
					(fill yes)
				)
			)
		)
		(pad "2" smd custom
			(at 0 0.4445)
			(size 0.1397 0.1397)
			(layers "F.Cu" "F.Mask" "F.Paste")
			(net "HDD_PRE_IO_INT_N")
			(options
				(clearance outline)
				(anchor circle)
			)
			(primitives
				(gr_poly
					(pts
						(arc
							(start -0.1778 -0.2794)
							(mid -0.249642 -0.249642)
							(end -0.2794 -0.1778)
						)
						(arc
							(start -0.2794 0.1778)
							(mid -0.249642 0.249642)
							(end -0.1778 0.2794)
						)
						(arc
							(start 0.1778 0.2794)
							(mid 0.249642 0.249642)
							(end 0.2794 0.1778)
						)
						(arc
							(start 0.2794 -0.1778)
							(mid 0.249642 -0.249642)
							(end 0.1778 -0.2794)
						)
					)
					(width 0)
					(fill yes)
				)
			)
		)
	)
	(footprint ""
		(layer "F.Cu")
		(at 336.071718 -157.584648 180)
		(property "Reference" "R7899"
			(at 0 0 180)
			(layer "F.SilkS")
			(hide yes)
			(effects
				(font
					(size 1.27 1.27)
				)
			)
		)
		(property "Value" "4K7R2F-GP"
			(at 0.064008 -3.993896 180)
			(unlocked yes)
			(layer "F.Fab")
			(hide yes)
			(effects
				(font
					(size 1.016 1.016)
					(thickness 0.1524)
				)
			)
		)
		(property "Device Type" "R402H16"
			(at 0.064008 -5.517896 180)
			(unlocked yes)
			(layer "F.Fab")
			(hide yes)
			(effects
				(font
					(size 1.016 1.016)
					(thickness 0.1524)
				)
			)
		)
		(duplicate_pad_numbers_are_jumpers no)
		(fp_line
			(start 0.508 -0.9398)
			(end -0.508 -0.9398)
			(stroke
				(width 0.1524)
				(type default)
			)
			(layer "F.SilkS")
		)
		(fp_line
			(start -0.508 -0.9398)
			(end -0.508 0.9398)
			(stroke
				(width 0.1524)
				(type default)
			)
			(layer "F.SilkS")
		)
		(fp_rect
			(start -0.508 0.9398)
			(end 0.508 -0.9398)
			(stroke
				(width 0)
				(type default)
			)
			(fill no)
			(layer "F.CrtYd")
		)
		(fp_rect
			(start -0.508 0.9398)
			(end 0.508 -0.9398)
			(stroke
				(width 0)
				(type default)
			)
			(fill no)
			(layer "F.Fab")
		)
		(pad "1" smd custom
			(at 0 -0.4445 180)
			(size 0.1397 0.1397)
			(layers "F.Cu" "F.Mask" "F.Paste")
			(net "USB_EN_3")
			(options
				(clearance outline)
				(anchor circle)
			)
			(primitives
				(gr_poly
					(pts
						(arc
							(start -0.1778 -0.2794)
							(mid -0.249642 -0.249642)
							(end -0.2794 -0.1778)
						)
						(arc
							(start -0.2794 0.1778)
							(mid -0.249642 0.249642)
							(end -0.1778 0.2794)
						)
						(arc
							(start 0.1778 0.2794)
							(mid 0.249642 0.249642)
							(end 0.2794 0.1778)
						)
						(arc
							(start 0.2794 -0.1778)
							(mid 0.249642 -0.249642)
							(end 0.1778 -0.2794)
						)
					)
					(width 0)
					(fill yes)
				)
			)
		)
		(pad "2" smd custom
			(at 0 0.4445 180)
			(size 0.1397 0.1397)
			(layers "F.Cu" "F.Mask" "F.Paste")
			(net "GND")
			(options
				(clearance outline)
				(anchor circle)
			)
			(primitives
				(gr_poly
					(pts
						(arc
							(start -0.1778 -0.2794)
							(mid -0.249642 -0.249642)
							(end -0.2794 -0.1778)
						)
						(arc
							(start -0.2794 0.1778)
							(mid -0.249642 0.249642)
							(end -0.1778 0.2794)
						)
						(arc
							(start 0.1778 0.2794)
							(mid 0.249642 0.249642)
							(end 0.2794 0.1778)
						)
						(arc
							(start 0.2794 -0.1778)
							(mid 0.249642 -0.249642)
							(end 0.1778 -0.2794)
						)
					)
					(width 0)
					(fill yes)
				)
			)
		)
	)
)
